(kicad_pcb
	(version 20260206)
	(generator "pcbnew")
	(generator_version "10.0")
	(general
		(thickness 1.6)
		(legacy_teardrops no)
	)
	(paper "A4")
	(title_block
		(title "01162023_DA0F0TEBIF0_F0T_Expander_BD_F_brd_V02_OCP.brd")
		(comment 1 "Grand Teton / footprints 3016-3021 of 9728")
	)
	(layers
		(0 "F.Cu" signal "TOP")
		(4 "In1.Cu" signal "GND")
		(6 "In2.Cu" signal "VCC")
		(8 "In3.Cu" signal "VCC1")
		(10 "In4.Cu" signal "GND1")
		(12 "In5.Cu" signal "IN1")
		(14 "In6.Cu" signal "GND2")
		(16 "In7.Cu" signal "IN2")
		(18 "In8.Cu" signal "GND3")
		(20 "In9.Cu" signal "IN3")
		(22 "In10.Cu" signal "GND4")
		(24 "In11.Cu" signal "IN4")
		(26 "In12.Cu" signal "GND5")
		(28 "In13.Cu" signal "IN5")
		(30 "In14.Cu" signal "GND6")
		(32 "In15.Cu" signal "IN6")
		(34 "In16.Cu" signal "GND7")
		(2 "B.Cu" signal "BOTTOM")
		(9 "F.Adhes" user "F.Adhesive")
		(11 "B.Adhes" user "B.Adhesive")
		(13 "F.Paste" user "Package Geometry/Pastemask Top")
		(15 "B.Paste" user "Package Geometry/Pastemask Bottom")
		(5 "F.SilkS" user "Ref Des/Silkscreen Top")
		(7 "B.SilkS" user "Ref Des/Silkscreen Bottom")
		(1 "F.Mask" user "Board Geometry/Soldermask Top")
		(3 "B.Mask" user "Board Geometry/Soldermask Bottom")
		(17 "Dwgs.User" user "User.Drawings")
		(19 "Cmts.User" user "User.Comments")
		(21 "Eco1.User" user "User.Eco1")
		(23 "Eco2.User" user "User.Eco2")
		(25 "Edge.Cuts" user "Board Geometry/Outline")
		(27 "Margin" user)
		(31 "F.CrtYd" user "Package Geometry/Place Bound Top")
		(29 "B.CrtYd" user "Package Geometry/Place Bound Bottom")
		(35 "F.Fab" user "Ref Des/Assembly Top")
		(33 "B.Fab" user "Ref Des/Assembly Bottom")
	)
	(footprint ""
		(layer "F.Cu")
		(at 449.704968 -254.5969 -90)
		(property "Reference" "C4394"
			(at 0 0 270)
			(layer "F.SilkS")
			(hide yes)
			(effects
				(font
					(size 1.27 1.27)
				)
			)
		)
		(property "Value" ""
			(at 0 0 270)
			(layer "F.Fab")
			(effects
				(font
					(size 1.27 1.27)
				)
			)
		)
		(duplicate_pad_numbers_are_jumpers no)
		(fp_line
			(start -1.2954 0.5842)
			(end -1.2954 -0.5842)
			(stroke
				(width 0.1524)
				(type default)
			)
			(layer "F.SilkS")
		)
		(fp_line
			(start 1.2954 0.5842)
			(end -1.2954 0.5842)
			(stroke
				(width 0.1524)
				(type default)
			)
			(layer "F.SilkS")
		)
		(fp_line
			(start -1.2954 -0.5842)
			(end 1.2954 -0.5842)
			(stroke
				(width 0.1524)
				(type default)
			)
			(layer "F.SilkS")
		)
		(fp_line
			(start 1.2954 -0.5842)
			(end 1.2954 0.5842)
			(stroke
				(width 0.1524)
				(type default)
			)
			(layer "F.SilkS")
		)
		(fp_line
			(start -0.8636 0.4572)
			(end -0.8636 0.4064)
			(stroke
				(width 0.1)
				(type default)
			)
			(layer "F.Fab")
		)
		(fp_line
			(start 0.8636 0.4572)
			(end -0.8636 0.4572)
			(stroke
				(width 0.1)
				(type default)
			)
			(layer "F.Fab")
		)
		(fp_line
			(start -1.1938 0.4064)
			(end -1.1938 -0.4064)
			(stroke
				(width 0.1)
				(type default)
			)
			(layer "F.Fab")
		)
		(fp_line
			(start -0.8636 0.4064)
			(end -1.1938 0.4064)
			(stroke
				(width 0.1)
				(type default)
			)
			(layer "F.Fab")
		)
		(fp_line
			(start 0.8636 0.4064)
			(end 0.8636 0.4572)
			(stroke
				(width 0.1)
				(type default)
			)
			(layer "F.Fab")
		)
		(fp_line
			(start 1.1938 0.4064)
			(end 0.8636 0.4064)
			(stroke
				(width 0.1)
				(type default)
			)
			(layer "F.Fab")
		)
		(fp_line
			(start -1.1938 -0.4064)
			(end -0.8636 -0.4064)
			(stroke
				(width 0.1)
				(type default)
			)
			(layer "F.Fab")
		)
		(fp_line
			(start -0.8636 -0.4064)
			(end -0.8636 -0.4572)
			(stroke
				(width 0.1)
				(type default)
			)
			(layer "F.Fab")
		)
		(fp_line
			(start 0.8636 -0.4064)
			(end 1.1938 -0.4064)
			(stroke
				(width 0.1)
				(type default)
			)
			(layer "F.Fab")
		)
		(fp_line
			(start 1.1938 -0.4064)
			(end 1.1938 0.4064)
			(stroke
				(width 0.1)
				(type default)
			)
			(layer "F.Fab")
		)
		(fp_line
			(start -0.8636 -0.4572)
			(end 0.8636 -0.4572)
			(stroke
				(width 0.1)
				(type default)
			)
			(layer "F.Fab")
		)
		(fp_line
			(start 0.8636 -0.4572)
			(end 0.8636 -0.4064)
			(stroke
				(width 0.1)
				(type default)
			)
			(layer "F.Fab")
		)
		(pad "1" smd rect
			(at -0.7366 0 180)
			(size 0.7112 0.8128)
			(layers "F.Cu" "F.Mask" "F.Paste")
			(net "P1V25_SERDES_VDDPLL_PEX3_C0")
		)
		(pad "2" smd rect
			(at 0.7366 0 180)
			(size 0.7112 0.8128)
			(layers "F.Cu" "F.Mask" "F.Paste")
			(net "GND")
		)
	)
	(footprint ""
		(layer "F.Cu")
		(at 228.562662 -288.017204)
		(property "Reference" "PC236"
			(at 0 0 0)
			(layer "F.SilkS")
			(hide yes)
			(effects
				(font
					(size 1.27 1.27)
				)
			)
		)
		(property "Value" ""
			(at 0 0 0)
			(layer "F.Fab")
			(effects
				(font
					(size 1.27 1.27)
				)
			)
		)
		(duplicate_pad_numbers_are_jumpers no)
		(fp_line
			(start -0.7874 -0.4064)
			(end 0.7874 -0.4064)
			(stroke
				(width 0.1524)
				(type default)
			)
			(layer "F.SilkS")
		)
		(fp_line
			(start -0.7874 0.4064)
			(end -0.7874 -0.4064)
			(stroke
				(width 0.1524)
				(type default)
			)
			(layer "F.SilkS")
		)
		(fp_line
			(start 0.7874 -0.4064)
			(end 0.7874 0.4064)
			(stroke
				(width 0.1524)
				(type default)
			)
			(layer "F.SilkS")
		)
		(fp_line
			(start 0.7874 0.4064)
			(end -0.7874 0.4064)
			(stroke
				(width 0.1524)
				(type default)
			)
			(layer "F.SilkS")
		)
		(fp_line
			(start -0.67945 -0.305054)
			(end -0.12065 -0.305054)
			(stroke
				(width 0.1)
				(type default)
			)
			(layer "F.Fab")
		)
		(fp_line
			(start -0.67945 0.3048)
			(end -0.67945 -0.305054)
			(stroke
				(width 0.1)
				(type default)
			)
			(layer "F.Fab")
		)
		(fp_line
			(start -0.12065 -0.305054)
			(end -0.12065 -0.2794)
			(stroke
				(width 0.1)
				(type default)
			)
			(layer "F.Fab")
		)
		(fp_line
			(start -0.12065 -0.2794)
			(end 0.12065 -0.2794)
			(stroke
				(width 0.1)
				(type default)
			)
			(layer "F.Fab")
		)
		(fp_line
			(start -0.12065 0.2794)
			(end -0.12065 0.3048)
			(stroke
				(width 0.1)
				(type default)
			)
			(layer "F.Fab")
		)
		(fp_line
			(start -0.12065 0.3048)
			(end -0.67945 0.3048)
			(stroke
				(width 0.1)
				(type default)
			)
			(layer "F.Fab")
		)
		(fp_line
			(start 0.120396 0.2794)
			(end -0.12065 0.2794)
			(stroke
				(width 0.1)
				(type default)
			)
			(layer "F.Fab")
		)
		(fp_line
			(start 0.120396 0.3048)
			(end 0.120396 0.2794)
			(stroke
				(width 0.1)
				(type default)
			)
			(layer "F.Fab")
		)
		(fp_line
			(start 0.12065 -0.3048)
			(end 0.67945 -0.3048)
			(stroke
				(width 0.1)
				(type default)
			)
			(layer "F.Fab")
		)
		(fp_line
			(start 0.12065 -0.2794)
			(end 0.12065 -0.3048)
			(stroke
				(width 0.1)
				(type default)
			)
			(layer "F.Fab")
		)
		(fp_line
			(start 0.67945 -0.3048)
			(end 0.67945 0.3048)
			(stroke
				(width 0.1)
				(type default)
			)
			(layer "F.Fab")
		)
		(fp_line
			(start 0.67945 0.3048)
			(end 0.120396 0.3048)
			(stroke
				(width 0.1)
				(type default)
			)
			(layer "F.Fab")
		)
		(pad "1" smd circle
			(at -0.40005 0)
			(size 0 0)
			(layers "F.Cu" "F.Mask" "F.Paste")
			(net "P1V25_PEX1_R")
		)
		(pad "2" smd circle
			(at 0.40005 0)
			(size 0 0)
			(layers "F.Cu" "F.Mask" "F.Paste")
			(net "GND")
		)
	)
	(footprint ""
		(layer "F.Cu")
		(at 392.092434 -32.739584 180)
		(property "Reference" "C708"
			(at 0 0 180)
			(layer "F.SilkS")
			(hide yes)
			(effects
				(font
					(size 1.27 1.27)
				)
			)
		)
		(property "Value" ""
			(at 0 0 180)
			(layer "F.Fab")
			(effects
				(font
					(size 1.27 1.27)
				)
			)
		)
		(duplicate_pad_numbers_are_jumpers no)
		(fp_line
			(start 0.299974 0.150114)
			(end -0.299974 0.150114)
			(stroke
				(width 0.1)
				(type default)
			)
			(layer "F.Fab")
		)
		(fp_line
			(start 0.299974 -0.150114)
			(end 0.299974 0.150114)
			(stroke
				(width 0.1)
				(type default)
			)
			(layer "F.Fab")
		)
		(fp_line
			(start -0.299974 0.150114)
			(end -0.299974 -0.150114)
			(stroke
				(width 0.1)
				(type default)
			)
			(layer "F.Fab")
		)
		(fp_line
			(start -0.299974 -0.150114)
			(end 0.299974 -0.150114)
			(stroke
				(width 0.1)
				(type default)
			)
			(layer "F.Fab")
		)
		(pad "1" smd rect
			(at -0.2667 0 180)
			(size 0.3048 0.381)
			(layers "F.Cu" "F.Mask" "F.Paste")
			(net "P5E_PEX3_STN2_TX_DP<42>")
		)
		(pad "2" smd rect
			(at 0.2667 0 180)
			(size 0.3048 0.381)
			(layers "F.Cu" "F.Mask" "F.Paste")
			(net "P5E_PEX3_STN2_TX_C_DP<42>")
		)
	)
	(footprint ""
		(layer "F.Cu")
		(at 242.316 -216.408 90)
		(property "Reference" "R6590"
			(at 0 0 90)
			(layer "F.SilkS")
			(hide yes)
			(effects
				(font
					(size 1.27 1.27)
				)
			)
		)
		(property "Value" ""
			(at 0 0 90)
			(layer "F.Fab")
			(effects
				(font
					(size 1.27 1.27)
				)
			)
		)
		(duplicate_pad_numbers_are_jumpers no)
		(fp_line
			(start 0.7874 -0.4064)
			(end 0.7874 0.4064)
			(stroke
				(width 0.1524)
				(type default)
			)
			(layer "F.SilkS")
		)
		(fp_line
			(start -0.7874 -0.4064)
			(end 0.7874 -0.4064)
			(stroke
				(width 0.1524)
				(type default)
			)
			(layer "F.SilkS")
		)
		(fp_line
			(start 0.7874 0.4064)
			(end -0.7874 0.4064)
			(stroke
				(width 0.1524)
				(type default)
			)
			(layer "F.SilkS")
		)
		(fp_line
			(start -0.7874 0.4064)
			(end -0.7874 -0.4064)
			(stroke
				(width 0.1524)
				(type default)
			)
			(layer "F.SilkS")
		)
		(fp_line
			(start -0.12065 -0.305054)
			(end -0.12065 -0.2794)
			(stroke
				(width 0.1)
				(type default)
			)
			(layer "F.Fab")
		)
		(fp_line
			(start -0.67945 -0.305054)
			(end -0.12065 -0.305054)
			(stroke
				(width 0.1)
				(type default)
			)
			(layer "F.Fab")
		)
		(fp_line
			(start 0.67945 -0.3048)
			(end 0.67945 0.3048)
			(stroke
				(width 0.1)
				(type default)
			)
			(layer "F.Fab")
		)
		(fp_line
			(start 0.12065 -0.3048)
			(end 0.67945 -0.3048)
			(stroke
				(width 0.1)
				(type default)
			)
			(layer "F.Fab")
		)
		(fp_line
			(start 0.12065 -0.2794)
			(end 0.12065 -0.3048)
			(stroke
				(width 0.1)
				(type default)
			)
			(layer "F.Fab")
		)
		(fp_line
			(start -0.12065 -0.2794)
			(end 0.12065 -0.2794)
			(stroke
				(width 0.1)
				(type default)
			)
			(layer "F.Fab")
		)
		(fp_line
			(start 0.120396 0.2794)
			(end -0.12065 0.2794)
			(stroke
				(width 0.1)
				(type default)
			)
			(layer "F.Fab")
		)
		(fp_line
			(start -0.12065 0.2794)
			(end -0.12065 0.3048)
			(stroke
				(width 0.1)
				(type default)
			)
			(layer "F.Fab")
		)
		(fp_line
			(start 0.67945 0.3048)
			(end 0.120396 0.3048)
			(stroke
				(width 0.1)
				(type default)
			)
			(layer "F.Fab")
		)
		(fp_line
			(start 0.120396 0.3048)
			(end 0.120396 0.2794)
			(stroke
				(width 0.1)
				(type default)
			)
			(layer "F.Fab")
		)
		(fp_line
			(start -0.12065 0.3048)
			(end -0.67945 0.3048)
			(stroke
				(width 0.1)
				(type default)
			)
			(layer "F.Fab")
		)
		(fp_line
			(start -0.67945 0.3048)
			(end -0.67945 -0.305054)
			(stroke
				(width 0.1)
				(type default)
			)
			(layer "F.Fab")
		)
		(pad "1" smd circle
			(at -0.40005 0 90)
			(size 0 0)
			(layers "F.Cu" "F.Mask" "F.Paste")
			(net "P1V8_PLL0_PEX0_SCALED")
		)
		(pad "2" smd circle
			(at 0.40005 0 90)
			(size 0 0)
			(layers "F.Cu" "F.Mask" "F.Paste")
			(net "GND")
		)
	)
	(footprint ""
		(layer "F.Cu")
		(at 9.32942 -273.906488)
		(property "Reference" "R778"
			(at 0 0 0)
			(layer "F.SilkS")
			(hide yes)
			(effects
				(font
					(size 1.27 1.27)
				)
			)
		)
		(property "Value" ""
			(at 0 0 0)
			(layer "F.Fab")
			(effects
				(font
					(size 1.27 1.27)
				)
			)
		)
		(duplicate_pad_numbers_are_jumpers no)
		(fp_line
			(start -0.7874 -0.4064)
			(end 0.7874 -0.4064)
			(stroke
				(width 0.1524)
				(type default)
			)
			(layer "F.SilkS")
		)
		(fp_line
			(start -0.7874 0.4064)
			(end -0.7874 -0.4064)
			(stroke
				(width 0.1524)
				(type default)
			)
			(layer "F.SilkS")
		)
		(fp_line
			(start 0.7874 -0.4064)
			(end 0.7874 0.4064)
			(stroke
				(width 0.1524)
				(type default)
			)
			(layer "F.SilkS")
		)
		(fp_line
			(start 0.7874 0.4064)
			(end -0.7874 0.4064)
			(stroke
				(width 0.1524)
				(type default)
			)
			(layer "F.SilkS")
		)
		(fp_line
			(start -0.67945 -0.305054)
			(end -0.12065 -0.305054)
			(stroke
				(width 0.1)
				(type default)
			)
			(layer "F.Fab")
		)
		(fp_line
			(start -0.67945 0.3048)
			(end -0.67945 -0.305054)
			(stroke
				(width 0.1)
				(type default)
			)
			(layer "F.Fab")
		)
		(fp_line
			(start -0.12065 -0.305054)
			(end -0.12065 -0.2794)
			(stroke
				(width 0.1)
				(type default)
			)
			(layer "F.Fab")
		)
		(fp_line
			(start -0.12065 -0.2794)
			(end 0.12065 -0.2794)
			(stroke
				(width 0.1)
				(type default)
			)
			(layer "F.Fab")
		)
		(fp_line
			(start -0.12065 0.2794)
			(end -0.12065 0.3048)
			(stroke
				(width 0.1)
				(type default)
			)
			(layer "F.Fab")
		)
		(fp_line
			(start -0.12065 0.3048)
			(end -0.67945 0.3048)
			(stroke
				(width 0.1)
				(type default)
			)
			(layer "F.Fab")
		)
		(fp_line
			(start 0.120396 0.2794)
			(end -0.12065 0.2794)
			(stroke
				(width 0.1)
				(type default)
			)
			(layer "F.Fab")
		)
		(fp_line
			(start 0.120396 0.3048)
			(end 0.120396 0.2794)
			(stroke
				(width 0.1)
				(type default)
			)
			(layer "F.Fab")
		)
		(fp_line
			(start 0.12065 -0.3048)
			(end 0.67945 -0.3048)
			(stroke
				(width 0.1)
				(type default)
			)
			(layer "F.Fab")
		)
		(fp_line
			(start 0.12065 -0.2794)
			(end 0.12065 -0.3048)
			(stroke
				(width 0.1)
				(type default)
			)
			(layer "F.Fab")
		)
		(fp_line
			(start 0.67945 -0.3048)
			(end 0.67945 0.3048)
			(stroke
				(width 0.1)
				(type default)
			)
			(layer "F.Fab")
		)
		(fp_line
			(start 0.67945 0.3048)
			(end 0.120396 0.3048)
			(stroke
				(width 0.1)
				(type default)
			)
			(layer "F.Fab")
		)
		(pad "1" smd circle
			(at -0.40005 0)
			(size 0 0)
			(layers "F.Cu" "F.Mask" "F.Paste")
			(net "P1V25_PEX0")
		)
		(pad "2" smd circle
			(at 0.40005 0)
			(size 0 0)
			(layers "F.Cu" "F.Mask" "F.Paste")
			(net "P12V_PEX0_P1V25_VIN_N")
		)
	)
	(footprint ""
		(layer "F.Cu")
		(at 100.136198 -95.264224 -90)
		(property "Reference" "C2855"
			(at 0 0 270)
			(layer "F.SilkS")
			(hide yes)
			(effects
				(font
					(size 1.27 1.27)
				)
			)
		)
		(property "Value" ""
			(at 0 0 270)
			(layer "F.Fab")
			(effects
				(font
					(size 1.27 1.27)
				)
			)
		)
		(duplicate_pad_numbers_are_jumpers no)
		(fp_line
			(start -0.7874 0.4064)
			(end -0.7874 -0.4064)
			(stroke
				(width 0.1524)
				(type default)
			)
			(layer "F.SilkS")
		)
		(fp_line
			(start 0.7874 0.4064)
			(end -0.7874 0.4064)
			(stroke
				(width 0.1524)
				(type default)
			)
			(layer "F.SilkS")
		)
		(fp_line
			(start -0.7874 -0.4064)
			(end 0.7874 -0.4064)
			(stroke
				(width 0.1524)
				(type default)
			)
			(layer "F.SilkS")
		)
		(fp_line
			(start 0.7874 -0.4064)
			(end 0.7874 0.4064)
			(stroke
				(width 0.1524)
				(type default)
			)
			(layer "F.SilkS")
		)
		(fp_line
			(start -0.67945 0.3048)
			(end -0.67945 -0.305054)
			(stroke
				(width 0.1)
				(type default)
			)
			(layer "F.Fab")
		)
		(fp_line
			(start -0.12065 0.3048)
			(end -0.67945 0.3048)
			(stroke
				(width 0.1)
				(type default)
			)
			(layer "F.Fab")
		)
		(fp_line
			(start 0.120396 0.3048)
			(end 0.120396 0.2794)
			(stroke
				(width 0.1)
				(type default)
			)
			(layer "F.Fab")
		)
		(fp_line
			(start 0.67945 0.3048)
			(end 0.120396 0.3048)
			(stroke
				(width 0.1)
				(type default)
			)
			(layer "F.Fab")
		)
		(fp_line
			(start -0.12065 0.2794)
			(end -0.12065 0.3048)
			(stroke
				(width 0.1)
				(type default)
			)
			(layer "F.Fab")
		)
		(fp_line
			(start 0.120396 0.2794)
			(end -0.12065 0.2794)
			(stroke
				(width 0.1)
				(type default)
			)
			(layer "F.Fab")
		)
		(fp_line
			(start -0.12065 -0.2794)
			(end 0.12065 -0.2794)
			(stroke
				(width 0.1)
				(type default)
			)
			(layer "F.Fab")
		)
		(fp_line
			(start 0.12065 -0.2794)
			(end 0.12065 -0.3048)
			(stroke
				(width 0.1)
				(type default)
			)
			(layer "F.Fab")
		)
		(fp_line
			(start 0.12065 -0.3048)
			(end 0.67945 -0.3048)
			(stroke
				(width 0.1)
				(type default)
			)
			(layer "F.Fab")
		)
		(fp_line
			(start 0.67945 -0.3048)
			(end 0.67945 0.3048)
			(stroke
				(width 0.1)
				(type default)
			)
			(layer "F.Fab")
		)
		(fp_line
			(start -0.67945 -0.305054)
			(end -0.12065 -0.305054)
			(stroke
				(width 0.1)
				(type default)
			)
			(layer "F.Fab")
		)
		(fp_line
			(start -0.12065 -0.305054)
			(end -0.12065 -0.2794)
			(stroke
				(width 0.1)
				(type default)
			)
			(layer "F.Fab")
		)
		(pad "1" smd circle
			(at -0.40005 0 270)
			(size 0 0)
			(layers "F.Cu" "F.Mask" "F.Paste")
			(net "P12V_NIC1_EN_R")
		)
		(pad "2" smd circle
			(at 0.40005 0 270)
			(size 0 0)
			(layers "F.Cu" "F.Mask" "F.Paste")
			(net "GND")
		)
	)
)
